FILE_TYPE = CONNECTIVITY;
{Allegro Design Entry HDL 16.6-p007 (v16-6-112F) 10/10/2012}
"PAGE_NUMBER" = 64;
0"NC";
1"TP_P3E_CPU1_PE1_RSR3_TXN<15:8>";
2"TP_P3E_CPU1_PE1_MP_TXN<7:0>";
3"TP_P3E_CPU1_PE1_RSR3_TXP<15:8>";
4"TP_P3E_CPU1_PE1_MP_TXP<7:0>";
5"TP_P3E_CPU1_PE1_RSR3_RXN<15:8>";
6"TP_P3E_CPU1_PE1_MP_RXN<7:0>";
7"TP_P3E_CPU1_PE1_RSR3_RXP<15:8>";
8"TP_P3E_CPU1_PE1_MP_RXP<7:0>";
9"TP_P3E_CPU1_PE1_MP_RXP<0>";
10"TP_P3E_CPU1_PE1_MP_RXP<1>";
11"TP_P3E_CPU1_PE1_MP_RXP<2>";
12"TP_P3E_CPU1_PE1_MP_RXP<3>";
13"TP_P3E_CPU1_PE1_MP_RXN<0>";
14"TP_P3E_CPU1_PE1_MP_RXN<1>";
15"TP_P3E_CPU1_PE1_MP_RXN<2>";
16"TP_P3E_CPU1_PE1_MP_RXN<3>";
17"TP_P3E_CPU1_PE1_MP_RXP<4>";
18"TP_P3E_CPU1_PE1_MP_RXP<5>";
19"TP_P3E_CPU1_PE1_MP_RXP<6>";
20"TP_P3E_CPU1_PE1_MP_RXP<7>";
21"TP_P3E_CPU1_PE1_RSR3_RXP<8>";
22"TP_P3E_CPU1_PE1_RSR3_RXP<9>";
23"TP_P3E_CPU1_PE1_RSR3_RXP<10>";
24"TP_P3E_CPU1_PE1_RSR3_RXP<11>";
25"TP_P3E_CPU1_PE1_RSR3_RXP<12>";
26"TP_P3E_CPU1_PE1_RSR3_RXP<13>";
27"TP_P3E_CPU1_PE1_RSR3_RXP<14>";
28"TP_P3E_CPU1_PE1_RSR3_RXP<15>";
29"TP_P3E_CPU1_PE1_MP_RXN<4>";
30"TP_P3E_CPU1_PE1_MP_RXN<5>";
31"TP_P3E_CPU1_PE1_MP_RXN<6>";
32"TP_P3E_CPU1_PE1_MP_RXN<7>";
33"TP_P3E_CPU1_PE1_RSR3_RXN<8>";
34"TP_P3E_CPU1_PE1_RSR3_RXN<9>";
35"TP_P3E_CPU1_PE1_RSR3_RXN<10>";
36"TP_P3E_CPU1_PE1_RSR3_RXN<11>";
37"TP_P3E_CPU1_PE1_RSR3_RXN<12>";
38"TP_P3E_CPU1_PE1_RSR3_RXN<13>";
39"TP_P3E_CPU1_PE1_RSR3_RXN<14>";
40"TP_P3E_CPU1_PE1_RSR3_RXN<15>";
41"TP_P3E_CPU1_PE1_MP_TXP<0>";
42"TP_P3E_CPU1_PE1_MP_TXP<1>";
43"TP_P3E_CPU1_PE1_MP_TXP<2>";
44"TP_P3E_CPU1_PE1_MP_TXP<3>";
45"TP_P3E_CPU1_PE1_MP_TXN<0>";
46"TP_P3E_CPU1_PE1_MP_TXN<1>";
47"TP_P3E_CPU1_PE1_MP_TXN<2>";
48"TP_P3E_CPU1_PE1_MP_TXN<3>";
49"TP_P3E_CPU1_PE1_MP_TXP<4>";
50"TP_P3E_CPU1_PE1_MP_TXP<5>";
51"TP_P3E_CPU1_PE1_MP_TXP<6>";
52"TP_P3E_CPU1_PE1_MP_TXP<7>";
53"TP_P3E_CPU1_PE1_RSR3_TXP<8>";
54"TP_P3E_CPU1_PE1_RSR3_TXP<9>";
55"TP_P3E_CPU1_PE1_RSR3_TXP<10>";
56"TP_P3E_CPU1_PE1_RSR3_TXP<11>";
57"TP_P3E_CPU1_PE1_RSR3_TXP<12>";
58"TP_P3E_CPU1_PE1_RSR3_TXP<13>";
59"TP_P3E_CPU1_PE1_RSR3_TXP<14>";
60"TP_P3E_CPU1_PE1_RSR3_TXP<15>";
61"TP_P3E_CPU1_PE1_MP_TXN<4>";
62"TP_P3E_CPU1_PE1_MP_TXN<5>";
63"TP_P3E_CPU1_PE1_MP_TXN<6>";
64"TP_P3E_CPU1_PE1_MP_TXN<7>";
65"TP_P3E_CPU1_PE1_RSR3_TXN<8>";
66"TP_P3E_CPU1_PE1_RSR3_TXN<9>";
67"TP_P3E_CPU1_PE1_RSR3_TXN<10>";
68"TP_P3E_CPU1_PE1_RSR3_TXN<11>";
69"TP_P3E_CPU1_PE1_RSR3_TXN<12>";
70"TP_P3E_CPU1_PE1_RSR3_TXN<13>";
71"TP_P3E_CPU1_PE1_RSR3_TXN<14>";
72"TP_P3E_CPU1_PE1_RSR3_TXN<15>";
%"TAP"
"1","(-5500,2125)","2","mstr_standard","I10";
;
HDL_TAP"TRUE"
BODY_TYPE"PLUMBING"
CDS_LIB"mstr_standard";
"B \NAC \NWC"6;
"S \NAC"
BN"4"29;
%"TAP"
"1","(-5500,2175)","2","mstr_standard","I11";
;
HDL_TAP"TRUE"
BODY_TYPE"PLUMBING"
CDS_LIB"mstr_standard";
"B \NAC \NWC"6;
"S \NAC"
BN"5"30;
%"TAP"
"1","(-5500,2275)","2","mstr_standard","I12";
;
HDL_TAP"TRUE"
BODY_TYPE"PLUMBING"
CDS_LIB"mstr_standard";
"B \NAC \NWC"6;
"S \NAC"
BN"7"32;
%"TAP"
"1","(-5500,2225)","2","mstr_standard","I13";
;
HDL_TAP"TRUE"
BODY_TYPE"PLUMBING"
CDS_LIB"mstr_standard";
"B \NAC \NWC"6;
"S \NAC"
BN"6"31;
%"TAP"
"1","(-5350,1975)","2","mstr_standard","I14";
;
HDL_TAP"TRUE"
BODY_TYPE"PLUMBING"
CDS_LIB"mstr_standard";
"B \NAC \NWC"8;
"S \NAC"
BN"2"11;
%"TAP"
"1","(-5350,2025)","2","mstr_standard","I15";
;
HDL_TAP"TRUE"
BODY_TYPE"PLUMBING"
CDS_LIB"mstr_standard";
"B \NAC \NWC"8;
"S \NAC"
BN"3"12;
%"TAP"
"1","(-5350,2425)","2","mstr_standard","I16";
;
HDL_TAP"TRUE"
BODY_TYPE"PLUMBING"
CDS_LIB"mstr_standard";
"B \NAC \NWC"8;
"S \NAC"
BN"5"18;
%"TAP"
"1","(-5350,2375)","2","mstr_standard","I17";
;
HDL_TAP"TRUE"
BODY_TYPE"PLUMBING"
CDS_LIB"mstr_standard";
"B \NAC \NWC"8;
"S \NAC"
BN"4"17;
%"TAP"
"1","(-5350,2475)","2","mstr_standard","I18";
;
HDL_TAP"TRUE"
BODY_TYPE"PLUMBING"
CDS_LIB"mstr_standard";
"B \NAC \NWC"8;
"S \NAC"
BN"6"19;
%"TAP"
"1","(-5500,2625)","2","mstr_standard","I19";
;
HDL_TAP"TRUE"
BODY_TYPE"PLUMBING"
CDS_LIB"mstr_standard";
"B \NAC \NWC"5;
"S \NAC"
BN"8"33;
%"TAP"
"1","(-5500,2675)","2","mstr_standard","I20";
;
HDL_TAP"TRUE"
BODY_TYPE"PLUMBING"
CDS_LIB"mstr_standard";
"B \NAC \NWC"5;
"S \NAC"
BN"9"34;
%"TAP"
"1","(-5500,2725)","2","mstr_standard","I21";
;
HDL_TAP"TRUE"
BODY_TYPE"PLUMBING"
CDS_LIB"mstr_standard";
"B \NAC \NWC"5;
"S \NAC"
BN"10"35;
%"TAP"
"1","(-5500,2775)","2","mstr_standard","I22";
;
HDL_TAP"TRUE"
BODY_TYPE"PLUMBING"
CDS_LIB"mstr_standard";
"B \NAC \NWC"5;
"S \NAC"
BN"11"36;
%"TAP"
"1","(-5350,2525)","2","mstr_standard","I23";
;
HDL_TAP"TRUE"
BODY_TYPE"PLUMBING"
CDS_LIB"mstr_standard";
"B \NAC \NWC"8;
"S \NAC"
BN"7"20;
%"TAP"
"1","(-5350,2875)","2","mstr_standard","I24";
;
HDL_TAP"TRUE"
BODY_TYPE"PLUMBING"
CDS_LIB"mstr_standard";
"B \NAC \NWC"7;
"S \NAC"
BN"8"21;
%"TAP"
"1","(-5350,2925)","2","mstr_standard","I25";
;
HDL_TAP"TRUE"
BODY_TYPE"PLUMBING"
CDS_LIB"mstr_standard";
"B \NAC \NWC"7;
"S \NAC"
BN"9"22;
%"TAP"
"1","(-5350,2975)","2","mstr_standard","I26";
;
HDL_TAP"TRUE"
BODY_TYPE"PLUMBING"
CDS_LIB"mstr_standard";
"B \NAC \NWC"7;
"S \NAC"
BN"10"23;
%"TAP"
"1","(-5500,3225)","2","mstr_standard","I27";
;
HDL_TAP"TRUE"
BODY_TYPE"PLUMBING"
CDS_LIB"mstr_standard";
"B \NAC \NWC"5;
"S \NAC"
BN"14"39;
%"TAP"
"1","(-5500,3175)","2","mstr_standard","I28";
;
HDL_TAP"TRUE"
BODY_TYPE"PLUMBING"
CDS_LIB"mstr_standard";
"B \NAC \NWC"5;
"S \NAC"
BN"13"38;
%"TAP"
"1","(-5500,3125)","2","mstr_standard","I29";
;
HDL_TAP"TRUE"
BODY_TYPE"PLUMBING"
CDS_LIB"mstr_standard";
"B \NAC \NWC"5;
"S \NAC"
BN"12"37;
%"TAP"
"1","(-5500,1625)","2","mstr_standard","I3";
;
HDL_TAP"TRUE"
BODY_TYPE"PLUMBING"
CDS_LIB"mstr_standard";
"B \NAC \NWC"6;
"S \NAC"
BN"0"13;
%"TAP"
"1","(-5500,3275)","2","mstr_standard","I30";
;
HDL_TAP"TRUE"
BODY_TYPE"PLUMBING"
CDS_LIB"mstr_standard";
"B \NAC \NWC"5;
"S \NAC"
BN"15"40;
%"TAP"
"1","(-5350,3025)","2","mstr_standard","I31";
;
HDL_TAP"TRUE"
BODY_TYPE"PLUMBING"
CDS_LIB"mstr_standard";
"B \NAC \NWC"7;
"S \NAC"
BN"11"24;
%"TAP"
"1","(-5350,3375)","2","mstr_standard","I32";
;
HDL_TAP"TRUE"
BODY_TYPE"PLUMBING"
CDS_LIB"mstr_standard";
"B \NAC \NWC"7;
"S \NAC"
BN"12"25;
%"TAP"
"1","(-5350,3425)","2","mstr_standard","I33";
;
HDL_TAP"TRUE"
BODY_TYPE"PLUMBING"
CDS_LIB"mstr_standard";
"B \NAC \NWC"7;
"S \NAC"
BN"13"26;
%"TAP"
"1","(-5350,3475)","2","mstr_standard","I34";
;
HDL_TAP"TRUE"
BODY_TYPE"PLUMBING"
CDS_LIB"mstr_standard";
"B \NAC \NWC"7;
"S \NAC"
BN"14"27;
%"TAP"
"1","(-5350,3525)","2","mstr_standard","I35";
;
HDL_TAP"TRUE"
BODY_TYPE"PLUMBING"
CDS_LIB"mstr_standard";
"B \NAC \NWC"7;
"S \NAC"
BN"15"28;
%"TAP"
"1","(-2725,1625)","0","mstr_standard","I36";
;
HDL_TAP"TRUE"
BODY_TYPE"PLUMBING"
CDS_LIB"mstr_standard";
"B \NAC \NWC"2;
"S \NAC"
BN"0"45;
%"TAP"
"1","(-2725,1675)","0","mstr_standard","I37";
;
HDL_TAP"TRUE"
BODY_TYPE"PLUMBING"
CDS_LIB"mstr_standard";
"B \NAC \NWC"2;
"S \NAC"
BN"1"46;
%"TAP"
"1","(-2875,1925)","0","mstr_standard","I38";
;
HDL_TAP"TRUE"
BODY_TYPE"PLUMBING"
CDS_LIB"mstr_standard";
"B \NAC \NWC"4;
"S \NAC"
BN"1"42;
%"TAP"
"1","(-2875,1875)","0","mstr_standard","I39";
;
HDL_TAP"TRUE"
BODY_TYPE"PLUMBING"
CDS_LIB"mstr_standard";
"B \NAC \NWC"4;
"S \NAC"
BN"0"41;
%"TAP"
"1","(-5500,1675)","2","mstr_standard","I4";
;
HDL_TAP"TRUE"
BODY_TYPE"PLUMBING"
CDS_LIB"mstr_standard";
"B \NAC \NWC"6;
"S \NAC"
BN"1"14;
%"TAP"
"1","(-2725,1775)","0","mstr_standard","I40";
;
HDL_TAP"TRUE"
BODY_TYPE"PLUMBING"
CDS_LIB"mstr_standard";
"B \NAC \NWC"2;
"S \NAC"
BN"3"48;
%"TAP"
"1","(-2725,1725)","0","mstr_standard","I41";
;
HDL_TAP"TRUE"
BODY_TYPE"PLUMBING"
CDS_LIB"mstr_standard";
"B \NAC \NWC"2;
"S \NAC"
BN"2"47;
%"TAP"
"1","(-2875,2025)","0","mstr_standard","I42";
;
HDL_TAP"TRUE"
BODY_TYPE"PLUMBING"
CDS_LIB"mstr_standard";
"B \NAC \NWC"4;
"S \NAC"
BN"3"44;
%"TAP"
"1","(-2875,1975)","0","mstr_standard","I43";
;
HDL_TAP"TRUE"
BODY_TYPE"PLUMBING"
CDS_LIB"mstr_standard";
"B \NAC \NWC"4;
"S \NAC"
BN"2"43;
%"TAP"
"1","(-2725,2125)","0","mstr_standard","I44";
;
HDL_TAP"TRUE"
BODY_TYPE"PLUMBING"
CDS_LIB"mstr_standard";
"B \NAC \NWC"2;
"S \NAC"
BN"4"61;
%"TAP"
"1","(-2725,2175)","0","mstr_standard","I45";
;
HDL_TAP"TRUE"
BODY_TYPE"PLUMBING"
CDS_LIB"mstr_standard";
"B \NAC \NWC"2;
"S \NAC"
BN"5"62;
%"TAP"
"1","(-2725,2225)","0","mstr_standard","I46";
;
HDL_TAP"TRUE"
BODY_TYPE"PLUMBING"
CDS_LIB"mstr_standard";
"B \NAC \NWC"2;
"S \NAC"
BN"6"63;
%"TAP"
"1","(-2875,2375)","0","mstr_standard","I47";
;
HDL_TAP"TRUE"
BODY_TYPE"PLUMBING"
CDS_LIB"mstr_standard";
"B \NAC \NWC"4;
"S \NAC"
BN"4"49;
%"TAP"
"1","(-2875,2425)","0","mstr_standard","I48";
;
HDL_TAP"TRUE"
BODY_TYPE"PLUMBING"
CDS_LIB"mstr_standard";
"B \NAC \NWC"4;
"S \NAC"
BN"5"50;
%"TAP"
"1","(-2875,2475)","0","mstr_standard","I49";
;
HDL_TAP"TRUE"
BODY_TYPE"PLUMBING"
CDS_LIB"mstr_standard";
"B \NAC \NWC"4;
"S \NAC"
BN"6"51;
%"TAP"
"1","(-5500,1725)","2","mstr_standard","I5";
;
HDL_TAP"TRUE"
BODY_TYPE"PLUMBING"
CDS_LIB"mstr_standard";
"B \NAC \NWC"6;
"S \NAC"
BN"2"15;
%"TAP"
"1","(-2725,2275)","0","mstr_standard","I50";
;
HDL_TAP"TRUE"
BODY_TYPE"PLUMBING"
CDS_LIB"mstr_standard";
"B \NAC \NWC"2;
"S \NAC"
BN"7"64;
%"TAP"
"1","(-2875,2525)","0","mstr_standard","I51";
;
HDL_TAP"TRUE"
BODY_TYPE"PLUMBING"
CDS_LIB"mstr_standard";
"B \NAC \NWC"4;
"S \NAC"
BN"7"52;
%"TAP"
"1","(-2725,2625)","0","mstr_standard","I52";
;
HDL_TAP"TRUE"
BODY_TYPE"PLUMBING"
CDS_LIB"mstr_standard";
"B \NAC \NWC"1;
"S \NAC"
BN"8"65;
%"TAP"
"1","(-2725,2725)","0","mstr_standard","I53";
;
HDL_TAP"TRUE"
BODY_TYPE"PLUMBING"
CDS_LIB"mstr_standard";
"B \NAC \NWC"1;
"S \NAC"
BN"10"67;
%"TAP"
"1","(-2725,2675)","0","mstr_standard","I54";
;
HDL_TAP"TRUE"
BODY_TYPE"PLUMBING"
CDS_LIB"mstr_standard";
"B \NAC \NWC"1;
"S \NAC"
BN"9"66;
%"TAP"
"1","(-2875,2875)","0","mstr_standard","I55";
;
HDL_TAP"TRUE"
BODY_TYPE"PLUMBING"
CDS_LIB"mstr_standard";
"B \NAC \NWC"3;
"S \NAC"
BN"8"53;
%"TAP"
"1","(-2875,2925)","0","mstr_standard","I56";
;
HDL_TAP"TRUE"
BODY_TYPE"PLUMBING"
CDS_LIB"mstr_standard";
"B \NAC \NWC"3;
"S \NAC"
BN"9"54;
%"TAP"
"1","(-2875,2975)","0","mstr_standard","I57";
;
HDL_TAP"TRUE"
BODY_TYPE"PLUMBING"
CDS_LIB"mstr_standard";
"B \NAC \NWC"3;
"S \NAC"
BN"10"55;
%"TAP"
"1","(-2725,2775)","0","mstr_standard","I58";
;
HDL_TAP"TRUE"
BODY_TYPE"PLUMBING"
CDS_LIB"mstr_standard";
"B \NAC \NWC"1;
"S \NAC"
BN"11"68;
%"TAP"
"1","(-2875,3025)","0","mstr_standard","I59";
;
HDL_TAP"TRUE"
BODY_TYPE"PLUMBING"
CDS_LIB"mstr_standard";
"B \NAC \NWC"3;
"S \NAC"
BN"11"56;
%"TAP"
"1","(-5500,1775)","2","mstr_standard","I6";
;
HDL_TAP"TRUE"
BODY_TYPE"PLUMBING"
CDS_LIB"mstr_standard";
"B \NAC \NWC"6;
"S \NAC"
BN"3"16;
%"TAP"
"1","(-2725,3125)","0","mstr_standard","I60";
;
HDL_TAP"TRUE"
BODY_TYPE"PLUMBING"
CDS_LIB"mstr_standard";
"B \NAC \NWC"1;
"S \NAC"
BN"12"69;
%"TAP"
"1","(-2725,3175)","0","mstr_standard","I61";
;
HDL_TAP"TRUE"
BODY_TYPE"PLUMBING"
CDS_LIB"mstr_standard";
"B \NAC \NWC"1;
"S \NAC"
BN"13"70;
%"TAP"
"1","(-2725,3225)","0","mstr_standard","I62";
;
HDL_TAP"TRUE"
BODY_TYPE"PLUMBING"
CDS_LIB"mstr_standard";
"B \NAC \NWC"1;
"S \NAC"
BN"14"71;
%"TAP"
"1","(-2875,3375)","0","mstr_standard","I63";
;
HDL_TAP"TRUE"
BODY_TYPE"PLUMBING"
CDS_LIB"mstr_standard";
"B \NAC \NWC"3;
"S \NAC"
BN"12"57;
%"TAP"
"1","(-2875,3425)","0","mstr_standard","I64";
;
HDL_TAP"TRUE"
BODY_TYPE"PLUMBING"
CDS_LIB"mstr_standard";
"B \NAC \NWC"3;
"S \NAC"
BN"13"58;
%"TAP"
"1","(-2875,3475)","0","mstr_standard","I65";
;
HDL_TAP"TRUE"
BODY_TYPE"PLUMBING"
CDS_LIB"mstr_standard";
"B \NAC \NWC"3;
"S \NAC"
BN"14"59;
%"TAP"
"1","(-2725,3275)","0","mstr_standard","I66";
;
HDL_TAP"TRUE"
BODY_TYPE"PLUMBING"
CDS_LIB"mstr_standard";
"B \NAC \NWC"1;
"S \NAC"
BN"15"72;
%"TAP"
"1","(-2875,3525)","0","mstr_standard","I67";
;
HDL_TAP"TRUE"
BODY_TYPE"PLUMBING"
CDS_LIB"mstr_standard";
"B \NAC \NWC"3;
"S \NAC"
BN"15"60;
%"SKX_EXT_B"
"10","(-4075,2575)","0","chpset_lib","I68";
;
CDS_SEC"10"
CDS_LOCATION"U2D1"
SEC"10"
CDS_LIB"chpset_lib"
SEC_TYPE"BGA1"
PACK_TYPE"BGA1"
MATERIAL"IC"
PART_NUMBER"TBD"
LOCATION"U2D1";
"PE1_TX_DP<0>"
$PN"CW2"41;
"PE1_TX_DP<1>"
$PN"DB1"42;
"PE1_TX_DP<2>"
$PN"DD3"43;
"PE1_TX_DP<3>"
$PN"DC4"44;
"PE1_TX_DP<4>"
$PN"DF3"49;
"PE1_TX_DP<5>"
$PN"DH3"50;
"PE1_TX_DP<6>"
$PN"DL2"51;
"PE1_TX_DP<7>"
$PN"DP3"52;
"PE1_TX_DP<8>"
$PN"DR4"53;
"PE1_TX_DP<9>"
$PN"DU2"54;
"PE1_TX_DP<10>"
$PN"DU4"55;
"PE1_TX_DP<11>"
$PN"DV5"56;
"PE1_TX_DP<12>"
$PN"DT7"57;
"PE1_TX_DP<13>"
$PN"DW6"58;
"PE1_TX_DP<14>"
$PN"EB7"59;
"PE1_TX_DP<15>"
$PN"EC8"60;
"PE1_TX_DN<0>"
$PN"DA2"45;
"PE1_TX_DN<1>"
$PN"DC2"46;
"PE1_TX_DN<2>"
$PN"DE2"47;
"PE1_TX_DN<3>"
$PN"DE4"48;
"PE1_TX_DN<4>"
$PN"DG4"61;
"PE1_TX_DN<5>"
$PN"DK3"62;
"PE1_TX_DN<6>"
$PN"DM3"63;
"PE1_TX_DN<7>"
$PN"DN4"64;
"PE1_TX_DN<8>"
$PN"DT5"65;
"PE1_TX_DN<9>"
$PN"DV3"66;
"PE1_TX_DN<10>"
$PN"DW4"67;
"PE1_TX_DN<11>"
$PN"DU6"68;
"PE1_TX_DN<12>"
$PN"DV7"69;
"PE1_TX_DN<13>"
$PN"DY7"70;
"PE1_TX_DN<14>"
$PN"EA8"71;
"PE1_TX_DN<15>"
$PN"ED9"72;
"PE1_RX_DP<0>"
$PN"CU8"9;
"PE1_RX_DP<1>"
$PN"CY7"10;
"PE1_RX_DP<2>"
$PN"DB9"11;
"PE1_RX_DP<3>"
$PN"DA10"12;
"PE1_RX_DP<4>"
$PN"DD9"17;
"PE1_RX_DP<5>"
$PN"DF9"18;
"PE1_RX_DP<6>"
$PN"DJ8"19;
"PE1_RX_DP<7>"
$PN"DL10"20;
"PE1_RX_DP<8>"
$PN"DK11"21;
"PE1_RX_DP<9>"
$PN"DN10"22;
"PE1_RX_DP<10>"
$PN"DR12"23;
"PE1_RX_DP<11>"
$PN"DP13"24;
"PE1_RX_DP<12>"
$PN"DU12"25;
"PE1_RX_DP<13>"
$PN"DY13"26;
"PE1_RX_DP<14>"
$PN"DV15"27;
"PE1_RX_DP<15>"
$PN"DT15"28;
"PE1_RX_DN<0>"
$PN"CW8"13;
"PE1_RX_DN<1>"
$PN"DA8"14;
"PE1_RX_DN<2>"
$PN"DC8"15;
"PE1_RX_DN<3>"
$PN"DC10"16;
"PE1_RX_DN<4>"
$PN"DE10"29;
"PE1_RX_DN<5>"
$PN"DH9"30;
"PE1_RX_DN<6>"
$PN"DK9"31;
"PE1_RX_DN<7>"
$PN"DM9"32;
"PE1_RX_DN<8>"
$PN"DM11"33;
"PE1_RX_DN<9>"
$PN"DP11"34;
"PE1_RX_DN<10>"
$PN"DT11"35;
"PE1_RX_DN<11>"
$PN"DT13"36;
"PE1_RX_DN<12>"
$PN"DV13"37;
"PE1_RX_DN<13>"
$PN"DW14"38;
"PE1_RX_DN<14>"
$PN"DY15"39;
"PE1_RX_DN<15>"
$PN"DU16"40;
%"TAP"
"1","(-5350,1875)","2","mstr_standard","I7";
;
HDL_TAP"TRUE"
BODY_TYPE"PLUMBING"
CDS_LIB"mstr_standard";
"B \NAC \NWC"8;
"S \NAC"
BN"0"9;
%"TAP"
"1","(-5350,1925)","2","mstr_standard","I8";
;
HDL_TAP"TRUE"
BODY_TYPE"PLUMBING"
CDS_LIB"mstr_standard";
"B \NAC \NWC"8;
"S \NAC"
BN"1"10;
END.
